FILE_TYPE = MACRO_DRAWING;
SET COLOR_WIRE YELLOW;
SET COLOR_PROP ORANGE;
SET COLOR_DOT WHITE;
SET COLOR_ARC YELLOW;
SET COLOR_BODY GREEN;
SET COLOR_NOTE PURPLE;
SET PROP_DISPLAY VALUE;
SET PAGE_NUMBER P115;
FORCEADD QUANTA_TITLE_BLOCK_C..1
(0 0);
FORCEPROP 1 LAST CUSTOM_TXT_CDS <NAME_2>
J 0
(-3175 50);
FORCEPROP 1 LAST CUSTOM_TXT_CDS <NAME_1>
J 0
(-3175 175);
FORCEPROP 1 LAST CUSTOM_TXT_CDS <Q_NUMBER>
J 0
(-1403 103);
DISPLAY 1.212766 (-1403 103);
FORCEPROP 1 LAST CUSTOM_TXT_CDS <Q_PROJ>
J 0
(-2382 102);
DISPLAY 1.212766 (-2382 102);
FORCEPROP 1 LAST CUSTOM_TXT_CDS <Q_REV>
J 0
(-184 103);
DISPLAY 1.212766 (-184 103);
FORCEPROP 1 LAST CUSTOM_TXT_CDS <CON_LAST_MODIFIED>
J 0
(-1885 15);
DISPLAY 0.978723 (-1885 15);
FORCEPROP 1 LAST CUSTOM_TXT_CDS <CON_PAGE_NUM> OF <CON_TOTAL_PAGES>
J 0
(-446 18);
DISPLAY 0.978723 (-446 18);
FORCEPROP 1 LAST Q_DEPT BU9
J 1
(-3763 49);
DISPLAY 1.957447 (-3763 49);
PAINT GREEN (-3763 49);
FORCEPROP 1 LAST Q_TITLE PCIE X32 SLOT2
J 0
(-9275 75);
DISPLAY 2.446809 (-9275 75);
PAINT GREEN (-9275 75);
FORCEPROP 2 LAST CDS_LIB pure_quanta
J 0
(0 0);
DISPLAY INVISIBLE (0 0);
FORCEPROP 1 LAST CDS_LMAN_SYM_OUTLINE -9475,6775,100,-125
J 0
(0 0);
DISPLAY 0.468085 (0 0);
PAINT GREEN (0 0);
DISPLAY INVISIBLE (0 0);
FORCEPROP 2 LAST PAGE_BORDER TRUE
J 0
(-7890 5250);
DISPLAY 0.638298 (-7890 5250);
PAINT PINK (-7890 5250);
DISPLAY INVISIBLE (-7890 5250);
FORCEPROP 1 LAST COMMENT_BODY TRUE
J 0
(12 -13);
DISPLAY 0.978723 (12 -13);
PAINT GREEN (12 -13);
DISPLAY INVISIBLE (12 -13);
FORCEPROP 2 LAST CDS_XR_PAGE_TITLE CR-115 : @T6G_MB_LIB.T6G(SCH_1):PAGE115
J 0
(-7890 5250);
DISPLAY 0.638298 (-7890 5250);
PAINT PINK (-7890 5250);
DISPLAY INVISIBLE (-7890 5250);
FORCEPROP 2 LAST CUSTOM_TXT_CDS <XR_PAGE_TITLE>
J 0
(-7890 5250);
DISPLAY 0.638298 (-7890 5250);
PAINT PINK (-7890 5250);
DISPLAY INVISIBLE (-7890 5250);
FORCEPROP 0 LAST CDS_CON_LAST_MODIFIED Wed Mar 09 16:40:58 2022
J 0
(-1885 15);
DISPLAY INVISIBLE (-1885 15);
QUIT
